# S9S_MB_2U (Grand Teton) — schematic netlist excerpt (pin names and nets, part order shuffled) for the footprints in the layout excerpt that follows; sources: Cadence DE-HDL packaged netlist, KiCad conversion of 03242023_DA0F0TMBIJ0_F0T_Motherboard_J_brd_V01_OCP.brd

C1558  Q_CAP_DIFFBUS  DIFF BUS_0.22UF 6.3V 20% X6S  pkg C0201  page 175 : \1\ = P5E_CPU0_PE4_TX_C_DN<10> ; \2\ = P5E_CPU0_PE4_TX_DN<10>
R1717  Q_RES  49.9 1% CHIP  pkg 0402LF  page 278 : A = PVNN_TERM_CPU0 ; B = SVID_CLK1_CPU0_R
C749  Q_CAP_DIFFBUS  DIFF BUS_0.22UF 6.3V 20% X6S  pkg C0201  page 176 : \1\ = P5E_CPU1_PE2_TX_C_DP<12> ; \2\ = P5E_CPU1_PE2_TX_DP<12>

(kicad_pcb
	(version 20260206)
	(generator "pcbnew")
	(generator_version "10.0")
	(general
		(thickness 1.6)
		(legacy_teardrops no)
	)
	(paper "A4")
	(title_block
		(title "03242023_DA0F0TMBIJ0_F0T_Motherboard_J_brd_V01_OCP.brd")
		(comment 1 "Grand Teton / footprints 148-150 of 6105")
	)
	(layers
		(0 "F.Cu" signal "TOP")
		(4 "In1.Cu" signal "GND")
		(6 "In2.Cu" signal "IN1")
		(8 "In3.Cu" signal "GND1")
		(10 "In4.Cu" signal "IN2")
		(12 "In5.Cu" signal "GND2")
		(14 "In6.Cu" signal "IN3")
		(16 "In7.Cu" signal "GND3")
		(18 "In8.Cu" signal "VCC")
		(20 "In9.Cu" signal "VCC1")
		(22 "In10.Cu" signal "GND4")
		(24 "In11.Cu" signal "IN4")
		(26 "In12.Cu" signal "GND5")
		(28 "In13.Cu" signal "IN5")
		(30 "In14.Cu" signal "GND6")
		(32 "In15.Cu" signal "IN6")
		(34 "In16.Cu" signal "GND7")
		(2 "B.Cu" signal "BOTTOM")
		(9 "F.Adhes" user "F.Adhesive")
		(11 "B.Adhes" user "B.Adhesive")
		(13 "F.Paste" user "Package Geometry/Pastemask Top")
		(15 "B.Paste" user "Package Geometry/Pastemask Bottom")
		(5 "F.SilkS" user "Ref Des/Silkscreen Top")
		(7 "B.SilkS" user "Ref Des/Silkscreen Bottom")
		(1 "F.Mask" user "Board Geometry/Soldermask Top")
		(3 "B.Mask" user "Board Geometry/Soldermask Bottom")
		(17 "Dwgs.User" user "User.Drawings")
		(19 "Cmts.User" user "User.Comments")
		(21 "Eco1.User" user "User.Eco1")
		(23 "Eco2.User" user "User.Eco2")
		(25 "Edge.Cuts" user "Board Geometry/Outline")
		(27 "Margin" user)
		(31 "F.CrtYd" user "Package Geometry/Place Bound Top")
		(29 "B.CrtYd" user "Package Geometry/Place Bound Bottom")
		(35 "F.Fab" user "Ref Des/Assembly Top")
		(33 "B.Fab" user "Ref Des/Assembly Bottom")
	)
	(footprint ""
		(layer "F.Cu")
		(at 439.262266 -123.664726 180)
		(property "Reference" "R1717"
			(at 0 0 180)
			(layer "F.SilkS")
			(hide yes)
			(effects
				(font
					(size 1.27 1.27)
				)
			)
		)
		(property "Value" ""
			(at 0 0 180)
			(layer "F.Fab")
			(effects
				(font
					(size 1.27 1.27)
				)
			)
		)
		(duplicate_pad_numbers_are_jumpers no)
		(fp_line
			(start 0.7874 0.4064)
			(end -0.7874 0.4064)
			(stroke
				(width 0.1524)
				(type default)
			)
			(layer "F.SilkS")
		)
		(fp_line
			(start 0.7874 -0.4064)
			(end 0.7874 0.4064)
			(stroke
				(width 0.1524)
				(type default)
			)
			(layer "F.SilkS")
		)
		(fp_line
			(start -0.7874 0.4064)
			(end -0.7874 -0.4064)
			(stroke
				(width 0.1524)
				(type default)
			)
			(layer "F.SilkS")
		)
		(fp_line
			(start -0.7874 -0.4064)
			(end 0.7874 -0.4064)
			(stroke
				(width 0.1524)
				(type default)
			)
			(layer "F.SilkS")
		)
		(fp_line
			(start 0.67945 0.3048)
			(end 0.120396 0.3048)
			(stroke
				(width 0.1)
				(type default)
			)
			(layer "F.Fab")
		)
		(fp_line
			(start 0.67945 -0.3048)
			(end 0.67945 0.3048)
			(stroke
				(width 0.1)
				(type default)
			)
			(layer "F.Fab")
		)
		(fp_line
			(start 0.12065 -0.2794)
			(end 0.12065 -0.3048)
			(stroke
				(width 0.1)
				(type default)
			)
			(layer "F.Fab")
		)
		(fp_line
			(start 0.12065 -0.3048)
			(end 0.67945 -0.3048)
			(stroke
				(width 0.1)
				(type default)
			)
			(layer "F.Fab")
		)
		(fp_line
			(start 0.120396 0.3048)
			(end 0.120396 0.2794)
			(stroke
				(width 0.1)
				(type default)
			)
			(layer "F.Fab")
		)
		(fp_line
			(start 0.120396 0.2794)
			(end -0.12065 0.2794)
			(stroke
				(width 0.1)
				(type default)
			)
			(layer "F.Fab")
		)
		(fp_line
			(start -0.12065 0.3048)
			(end -0.67945 0.3048)
			(stroke
				(width 0.1)
				(type default)
			)
			(layer "F.Fab")
		)
		(fp_line
			(start -0.12065 0.2794)
			(end -0.12065 0.3048)
			(stroke
				(width 0.1)
				(type default)
			)
			(layer "F.Fab")
		)
		(fp_line
			(start -0.12065 -0.2794)
			(end 0.12065 -0.2794)
			(stroke
				(width 0.1)
				(type default)
			)
			(layer "F.Fab")
		)
		(fp_line
			(start -0.12065 -0.305054)
			(end -0.12065 -0.2794)
			(stroke
				(width 0.1)
				(type default)
			)
			(layer "F.Fab")
		)
		(fp_line
			(start -0.67945 0.3048)
			(end -0.67945 -0.305054)
			(stroke
				(width 0.1)
				(type default)
			)
			(layer "F.Fab")
		)
		(fp_line
			(start -0.67945 -0.305054)
			(end -0.12065 -0.305054)
			(stroke
				(width 0.1)
				(type default)
			)
			(layer "F.Fab")
		)
		(pad "1" smd circle
			(at -0.40005 0 180)
			(size 0 0)
			(layers "F.Cu" "F.Mask" "F.Paste")
			(net "PVNN_TERM_CPU0")
		)
		(pad "2" smd circle
			(at 0.40005 0 180)
			(size 0 0)
			(layers "F.Cu" "F.Mask" "F.Paste")
			(net "SVID_CLK1_CPU0_R")
		)
	)
	(footprint ""
		(layer "F.Cu")
		(at 129.319274 -402.371052 -90)
		(property "Reference" "C749"
			(at 0 0 270)
			(layer "F.SilkS")
			(hide yes)
			(effects
				(font
					(size 1.27 1.27)
				)
			)
		)
		(property "Value" ""
			(at 0 0 270)
			(layer "F.Fab")
			(effects
				(font
					(size 1.27 1.27)
				)
			)
		)
		(duplicate_pad_numbers_are_jumpers no)
		(fp_line
			(start -0.299974 0.150114)
			(end -0.299974 -0.150114)
			(stroke
				(width 0.1)
				(type default)
			)
			(layer "F.Fab")
		)
		(fp_line
			(start 0.299974 0.150114)
			(end -0.299974 0.150114)
			(stroke
				(width 0.1)
				(type default)
			)
			(layer "F.Fab")
		)
		(fp_line
			(start -0.299974 -0.150114)
			(end 0.299974 -0.150114)
			(stroke
				(width 0.1)
				(type default)
			)
			(layer "F.Fab")
		)
		(fp_line
			(start 0.299974 -0.150114)
			(end 0.299974 0.150114)
			(stroke
				(width 0.1)
				(type default)
			)
			(layer "F.Fab")
		)
		(pad "1" smd rect
			(at -0.2667 0 270)
			(size 0.3048 0.381)
			(layers "F.Cu" "F.Mask" "F.Paste")
			(net "P5E_CPU1_PE2_TX_C_DP<12>")
		)
		(pad "2" smd rect
			(at 0.2667 0 270)
			(size 0.3048 0.381)
			(layers "F.Cu" "F.Mask" "F.Paste")
			(net "P5E_CPU1_PE2_TX_DP<12>")
		)
	)
	(footprint ""
		(layer "F.Cu")
		(at 334.587088 -402.371052 -90)
		(property "Reference" "C1558"
			(at 0 0 270)
			(layer "F.SilkS")
			(hide yes)
			(effects
				(font
					(size 1.27 1.27)
				)
			)
		)
		(property "Value" ""
			(at 0 0 270)
			(layer "F.Fab")
			(effects
				(font
					(size 1.27 1.27)
				)
			)
		)
		(duplicate_pad_numbers_are_jumpers no)
		(fp_line
			(start -0.299974 0.150114)
			(end -0.299974 -0.150114)
			(stroke
				(width 0.1)
				(type default)
			)
			(layer "F.Fab")
		)
		(fp_line
			(start 0.299974 0.150114)
			(end -0.299974 0.150114)
			(stroke
				(width 0.1)
				(type default)
			)
			(layer "F.Fab")
		)
		(fp_line
			(start -0.299974 -0.150114)
			(end 0.299974 -0.150114)
			(stroke
				(width 0.1)
				(type default)
			)
			(layer "F.Fab")
		)
		(fp_line
			(start 0.299974 -0.150114)
			(end 0.299974 0.150114)
			(stroke
				(width 0.1)
				(type default)
			)
			(layer "F.Fab")
		)
		(pad "1" smd rect
			(at -0.2667 0 270)
			(size 0.3048 0.381)
			(layers "F.Cu" "F.Mask" "F.Paste")
			(net "P5E_CPU0_PE4_TX_C_DN<10>")
		)
		(pad "2" smd rect
			(at 0.2667 0 270)
			(size 0.3048 0.381)
			(layers "F.Cu" "F.Mask" "F.Paste")
			(net "P5E_CPU0_PE4_TX_DN<10>")
		)
	)
)
